FILE_TYPE = CONNECTIVITY;
{Allegro Design Entry HDL 16.6-p007 (v16-6-112F) 10/10/2012}
"PAGE_NUMBER" = 269;
0"NC";
1"GND\g";
2"P3V3_STBY\g";
3"GND\g";
4"P3V3_STBY\g";
5"GND\g";
6"P1V05_PCH_STBY\g";
7"GND\g";
8"GND\g";
9"GND\g";
10"GND\g";
11"P3V3_STBY\g";
12"P3V3_STBY\g";
13"GND\g";
14"P3V3_STBY\g";
15"GND\g";
16"GND\g";
17"P3V3_STBY\g";
18"BMC_PREQ_BUF_N";
19"PU_GTL2014_3_DIR";
20"JTAG_BMC_TCK_BUF";
21"BMC_JTAG_SEL_N";
22"JTAG_BMC_TCK1";
23"XDP_TMS_R";
24"XDP_TDI_R";
25"PD_GTL2014_3_VREF";
26"JTAG_BMC_TCK0";
27"XDP_PCH_TCK1";
28"XDP_CPU_TCK0";
29"BMC_PREQ_BUF_N";
30"XDP_TRST_R_N";
31"JTAG_BMC_TRST_N";
32"BMC_JTAG_SEL_BUF";
33"XDP_TRST_N";
34"XDP_PCH_TCK1_R";
35"XDP_CPU_TCK0_R";
36"BMC_JTAG_SEL_BUF";
37"BMC_PREQ_N";
38"JTAG_BMC_TCK0";
39"JTAG_BMC_TRST_BUF_N";
40"XDP_PREQ_N";
41"XDP_CPU_PWR_DEBUG_N";
42"XDP_TDI";
43"XDP_TMS";
44"JTAG_BMC_TCK1";
45"JTAG_BMC_BUF_TDI";
46"JTAG_BMC_BUF_TMS";
47"BMC_PWR_DEBUG_BUF_N";
48"BMC_TCK_MUX_SEL";
49"BMC_JTAG_SEL_BUF";
50"JTAG_BMC_TCK";
%"RES"
"2","(-6100,2900)","1","mstr_discrete","I10";
;
TOLERANCE"1%"
MATERIAL"CHIP"
PART_NUMBER"G21796-026"
PACK_TYPE"0402"
WATTAGE"1/16W"
LOCATION"R25W167"
VALUE"1.00K"
ROOM"PROC_RSTS_PGOODS"
$SEC"1"
CDS_SEC"1"
CDS_LIB"mstr_discrete"
BOM_COST"PROC_SIDEBAND"
CDS_LOCATION"R25W167";
"A"
$PN"1"48;
"B"
$PN"2"15;
%"RES"
"2","(-4750,3500)","1","mstr_discrete","I11";
;
LOCATION"R25W168"
PACK_TYPE"0402"
VALUE"1.00K"
PART_NUMBER"G21796-026"
MATERIAL"CHIP"
WATTAGE"1/16W"
TOLERANCE"1%"
BOM_COST"PROC_SIDEBAND"
CDS_LIB"mstr_discrete"
CDS_SEC"1"
$SEC"1"
ROOM"PROC_RSTS_PGOODS"
CDS_LOCATION"R25W168";
"A"
$PN"1"38;
"B"
$PN"2"1;
%"RES"
"2","(-4750,3700)","1","mstr_discrete","I12";
;
LOCATION"R25W169"
WATTAGE"1/16W"
VALUE"1.00K"
PACK_TYPE"0402"
PART_NUMBER"G21796-026"
MATERIAL"CHIP"
TOLERANCE"1%"
BOM_COST"PROC_SIDEBAND"
CDS_LIB"mstr_discrete"
CDS_SEC"1"
$SEC"1"
ROOM"PROC_RSTS_PGOODS"
CDS_LOCATION"R25W169";
"A"
$PN"1"22;
"B"
$PN"2"1;
%"RES"
"2","(-4750,3900)","1","mstr_discrete","I13";
;
LOCATION"R25W170"
PART_NUMBER"G21796-026"
MATERIAL"CHIP"
TOLERANCE"1%"
VALUE"1.00K"
PACK_TYPE"0402"
WATTAGE"1/16W"
BOM_COST"PROC_SIDEBAND"
CDS_LIB"mstr_discrete"
CDS_SEC"1"
$SEC"1"
ROOM"PROC_RSTS_PGOODS"
CDS_LOCATION"R25W170";
"A"
$PN"1"39;
"B"
$PN"2"1;
%"GND"
"1","(-4100,3425)","0","mstr_symbols","I14";
;
VOLTAGE"0.0V"
SIZE"1B"
CDS_LIB"mstr_symbols"
BODY_TYPE"PLUMBING"
HDL_POWER"GND";
"A\NAC"1;
%"P3V3_STBY"
"1","(-6400,4100)","0","mstr_symbols","I15";
;
SIZE"1B"
CDS_LIB"mstr_symbols"
VOLTAGE"3.3V"
BODY_TYPE"PLUMBING"
HDL_POWER"P3V3_STBY";
"G\NAC"2;
%"RES"
"2","(-7650,6050)","0","mstr_discrete","I18";
;
LOCATION"R25W177"
TOLERANCE"1%"
VALUE"1.00K"
WATTAGE"1/16W"
MATERIAL"CHIP"
PART_NUMBER"G21796-026"
PACK_TYPE"0402"
ROOM"PROC_RSTS_PGOODS"
$SEC"1"
CDS_SEC"1"
CDS_LIB"mstr_discrete"
BOM_COST"PROC_SIDEBAND"
CDS_LOCATION"R25W177";
"A"
$PN"1"4;
"B"
$PN"2"18;
%"RES"
"2","(-7350,6050)","0","mstr_discrete","I19";
;
TOLERANCE"1%"
LOCATION"R25W178"
MATERIAL"CHIP"
WATTAGE"1/16W"
VALUE"1.00K"
PACK_TYPE"0402"
PART_NUMBER"G21796-026"
BOM_COST"PROC_SIDEBAND"
CDS_LIB"mstr_discrete"
CDS_SEC"1"
$SEC"1"
ROOM"PROC_RSTS_PGOODS"
CDS_LOCATION"R25W178";
"A"
$PN"1"4;
"B"
$PN"2"47;
%"RES"
"2","(-7050,6050)","0","mstr_discrete","I20";
;
VALUE"1.00K"
MATERIAL"CHIP"
PACK_TYPE"0402"
LOCATION"R25W160"
PART_NUMBER"G21796-026"
TOLERANCE"1%"
WATTAGE"1/16W"
ROOM"PROC_RSTS_PGOODS"
$SEC"1"
CDS_SEC"1"
CDS_LIB"mstr_discrete"
BOM_COST"PROC_SIDEBAND"
CDS_LOCATION"R25W160";
"A"
$PN"1"4;
"B"
$PN"2"45;
%"RES"
"2","(-6750,6050)","0","mstr_discrete","I21";
;
LOCATION"R25W161"
TOLERANCE"1%"
VALUE"1.00K"
MATERIAL"CHIP"
WATTAGE"1/16W"
PART_NUMBER"G21796-026"
PACK_TYPE"0402"
CDS_LOCATION"R25W161"
BOM_COST"PROC_SIDEBAND"
CDS_LIB"mstr_discrete"
CDS_SEC"1"
$SEC"1"
ROOM"PROC_RSTS_PGOODS";
"A"
$PN"1"4;
"B"
$PN"2"46;
%"RES"
"2","(-6450,6050)","0","mstr_discrete","I22";
;
LOCATION"R25W158"
VALUE"1.00K"
TOLERANCE"1%"
WATTAGE"1/16W"
MATERIAL"CHIP"
PART_NUMBER"G21796-026"
PACK_TYPE"0402"
BOM_COST"PROC_SIDEBAND"
CDS_LIB"mstr_discrete"
CDS_SEC"1"
$SEC"1"
ROOM"PROC_RSTS_PGOODS"
CDS_LOCATION"R25W158";
"A"
$PN"1"4;
"B"
$PN"2"19;
%"GND"
"1","(-6200,5875)","0","mstr_symbols","I23";
;
CDS_LIB"mstr_symbols"
SIZE"1B"
VOLTAGE"0.0V"
BODY_TYPE"PLUMBING"
HDL_POWER"GND";
"A\NAC"3;
%"RES"
"1","(-6050,6000)","0","mstr_discrete","I24";
;
PACK_TYPE"0402"
TOLERANCE"1%"
LOCATION"R25W159"
VALUE"1.00K"
WATTAGE"1/16W"
PART_NUMBER"G21796-026"
MATERIAL"CHIP"
CDS_SEC"1"
ROOM"PROC_RSTS_PGOODS"
SEC"1"
CDS_LIB"mstr_discrete"
SEC_TYPE"0402"
BOM_COST"PROC_SIDEBAND"
CDS_LOCATION"R25W159";
"B"
$PN"2"25;
"A"
$PN"1"3;
%"P3V3_STBY"
"1","(-7650,6350)","0","mstr_symbols","I25";
;
VOLTAGE"3.3V"
SIZE"1B"
CDS_LIB"mstr_symbols"
BODY_TYPE"PLUMBING"
HDL_POWER"P3V3_STBY";
"G\NAC"4;
%"CAP_A"
"1","(-5800,6050)","0","dev_discrete","I26";
;
PACK_TYPE"0402V"
TOLERANCE"10%"
VOLTAGE"6.3V"
LOCATION"C25W91"
VALUE"1.0UF"
PART_NUMBER"D97712-004"
MATERIAL"X6S"
CDS_LOCATION"C25W91"
BOM_COST"PROC_SIDEBAND"
CDS_LIB"dev_discrete"
CDS_SEC"1"
SEC_TYPE"0402V"
SEC"1"
ROOM"PROC_RSTS_PGOODS";
"B"
$PN"2"5;
"A"
$PN"1"4;
%"GND"
"1","(-5800,5875)","0","mstr_symbols","I27";
;
SIZE"1B"
CDS_LIB"mstr_symbols"
VOLTAGE"0.0V"
BODY_TYPE"PLUMBING"
HDL_POWER"GND";
"A\NAC"5;
%"P1V05_PCH_STBY"
"1","(-4000,4350)","0","mstr_symbols","I28";
;
CDS_LIB"mstr_symbols"
VOLTAGE"1.05V"
BODY_TYPE"PLUMBING"
HDL_POWER"P1V05_PCH_STBY";
"G\NAC"6;
%"GND"
"1","(-4400,5025)","0","mstr_symbols","I29";
;
CDS_LIB"mstr_symbols"
SIZE"1B"
VOLTAGE"0.0V"
BODY_TYPE"PLUMBING"
HDL_POWER"GND";
"A\NAC"7;
%"GND"
"1","(-3050,2825)","0","mstr_symbols","I31";
;
SIZE"1B"
CDS_LIB"mstr_symbols"
VOLTAGE"0.0V"
BODY_TYPE"PLUMBING"
HDL_POWER"GND";
"A\NAC"8;
%"CAP"
"1","(-3050,3000)","0","mstr_discrete","I32";
;
TOLERANCE"10%"
PACK_TYPE"0402"
VALUE"1.0UF"
VOLTAGE"16V"
LOCATION"C25W94"
MATERIAL"X6S"
PART_NUMBER"D97712-011"
ROOM"DEBUG"
SEC"1"
SEC_TYPE"0402"
CDS_LIB"mstr_discrete"
CDS_LOCATION"C25W94"
CDS_SEC"1";
"A"
$PN"1"12;
"B"
$PN"2"8;
%"TTL3126"
"3","(-3700,3750)","0","mstr_ttl","I33";
;
PART_NUMBER"D18317-001"
POWER_GROUP"VCC=P3V3_STBY;GND=GND"
LOCATION"U25W12"
MATERIAL"IC"
VALUE"74CBTLV3126"
PACK_TYPE"QFNLF"
HAS_FIXED_SIZE"4B"
CDS_LIB"mstr_ttl"
ROOM"DEBUG"
CDS_LOCATION"U25W12";
"OE <3>"
$PN"1"
CDS_SEC"1"
$SEC"1"36;
"OE <2>"
$PN"4"
CDS_SEC"2"
$SEC"2"38;
"OE <1>"
$PN"10"
CDS_SEC"3"
$SEC"3"22;
"OE <0>"
$PN"13"
CDS_SEC"4"
$SEC"4"39;
"A <3>"
$PN"2"
CDS_SEC"1"
$SEC"1"37;
"A <2>"
$PN"5"
CDS_SEC"2"
$SEC"2"6;
"A <0>"
$PN"12"
CDS_SEC"4"
$SEC"4"6;
"A <1>"
$PN"9"
CDS_SEC"3"
$SEC"3"6;
"B <3>"
$PN"3"
CDS_SEC"1"
$SEC"1"29;
"B <2>"
$PN"6"
CDS_SEC"2"
$SEC"2"35;
"B <1>"
$PN"8"
CDS_SEC"3"
$SEC"3"34;
"B <0>"
$PN"11"
CDS_SEC"4"
$SEC"4"30;
%"RES"
"2","(-6400,3850)","0","mstr_discrete","I4";
;
PART_NUMBER"G21796-016"
WATTAGE"1/16W"
MATERIAL"CHIP"
TOLERANCE"1%"
LOCATION"R25W174"
VALUE"10.0K"
PACK_TYPE"0402"
SEC_TYPE"0402"
SEC"1"
BOM_COST"PROC_SIDEBAND"
CDS_LIB"mstr_discrete"
ROOM"CPU0"
CDS_LOCATION"R25W174"
CDS_SEC"1";
"A"
$PN"1"2;
"B"
$PN"2"21;
%"GTL2014"
"1","(-4950,5500)","0","mstr_digital","I49";
;
MATERIAL"IC"
LOCATION"U25W10"
PART_NUMBER"D66151-001"
CDS_LOCATION"U25W10"
PACK_TYPE"SM"
BOM_COST"PROC_SIDEBAND"
CDS_LIB"mstr_digital"
CDS_SEC"1"
$SEC"1"
ROOM"PROC_RSTS_PGOODS";
"A0"
$PN"13"18;
"A1"
$PN"12"47;
"A3"
$PN"9"46;
"A2"
$PN"10"45;
"B2"
$PN"5"24;
"B3"
$PN"6"23;
"B0"
$PN"2"40;
"B1"
$PN"3"41;
"GND<1>"
$PN"8"7;
"GND<2>"
$PN"11"7;
"GND<0>"
$PN"7"7;
"VCC"
$PN"14"4;
"VREF"
$PN"4"25;
"DIR"
$PN"1"19;
%"MAX4564EKA-GP"
"1","(-7075,3625)","0","w_hdl","I53";
;
CDS_SEC"1"
CDS_LOCATION"U25W13"
LOCATION"U25W13"
VALUE"MAX4564EKA-GP"
CDS_LMAN_SYM_OUTLINE"-225,175,225,-175"
CDS_LIB"w_hdl"
PART_NUMBER"074.04564.0099"
SEC_TYPE"SCRET-GC1"
SEC"1"
PACK_TYPE"SCRET-GC1";
"COM"
$PN"8"20;
"EN# \B"
$PN"7"21;
"V-"
$PN"6"9;
"GND"
$PN"5"9;
"NO"
$PN"4"44;
"IN"
$PN"3"48;
"V+"
$PN"2"11;
"NC"
$PN"1"26;
%"GND"
"1","(-6600,3475)","0","mstr_symbols","I54";
;
SIZE"1B"
VOLTAGE"0.0V"
CDS_LIB"mstr_symbols"
BODY_TYPE"PLUMBING"
HDL_POWER"GND";
"A\NAC"9;
%"CAP_A"
"1","(-8700,3850)","0","dev_discrete","I56";
;
VALUE"0.1UF"
PART_NUMBER"A36096-030"
PACK_TYPE"0402V"
MATERIAL"X7R"
TOLERANCE"10%"
LOCATION"C25W95"
VOLTAGE"16V"
CDS_LOCATION"C25W95"
ROOM"UART_MUX"
SEC"1"
CDS_SEC"1"
BOM_COST"DEBUG"
SEC_TYPE"0402V"
CDS_LIB"dev_discrete";
"B"
$PN"2"10;
"A"
$PN"1"11;
%"GND"
"1","(-8700,3675)","0","mstr_symbols","I57";
;
SIZE"1B"
VOLTAGE"0.0V"
CDS_LIB"mstr_symbols"
BODY_TYPE"PLUMBING"
HDL_POWER"GND";
"A\NAC"10;
%"P3V3_STBY"
"1","(-8700,4150)","0","mstr_symbols","I58";
;
VOLTAGE"3.3V"
CDS_LIB"mstr_symbols"
SIZE"1B"
BODY_TYPE"PLUMBING"
HDL_POWER"P3V3_STBY";
"G\NAC"11;
%"P3V3_STBY"
"1","(-3050,3200)","0","mstr_symbols","I60";
;
VOLTAGE"3.3V"
CDS_LIB"mstr_symbols"
SIZE"1B"
BODY_TYPE"PLUMBING"
HDL_POWER"P3V3_STBY";
"G\NAC"12;
%"TTL1G08"
"1","(-5100,4000)","0","mstr_ttl","I61";
;
POWER_GROUP"VCC=P3V3_STBY;GND=GND;"
PART_NUMBER"D10321-001"
LOCATION"U25W17"
MATERIAL"IC"
PACK_TYPE"SOTLF"
VALUE"NC7SZ08"
BOM_COST"PROC_SIDEBAND"
CDS_LIB"mstr_ttl"
SEC_TYPE"SOTLF"
SEC"1"
ROOM"CAT_ERR"
CDS_SEC"1"
CDS_LOCATION"U25W17";
"Y <SIZE-1..0>"
$PN"4"39;
"B <SIZE-1..0>"
$PN"2"32;
"A <SIZE-1..0>"
$PN"1"31;
%"CAP_A"
"1","(-5350,4450)","0","dev_discrete","I62";
;
TOLERANCE"10%"
PART_NUMBER"A36096-030"
PACK_TYPE"0402V"
VALUE"0.1UF"
LOCATION"C25W99"
MATERIAL"X7R"
VOLTAGE"16V"
CDS_LOCATION"C25W99"
SEC"1"
SEC_TYPE"0402V"
CDS_SEC"1"
CDS_LIB"dev_discrete"
BOM_COST"PROC_SIDEBAND"
ROOM"PROC_SIDEBAND";
"B"
$PN"2"13;
"A"
$PN"1"14;
%"GND"
"1","(-5350,4275)","0","mstr_symbols","I63";
;
CDS_LIB"mstr_symbols"
SIZE"1B"
VOLTAGE"0.0V"
BODY_TYPE"PLUMBING"
HDL_POWER"GND";
"A\NAC"13;
%"P3V3_STBY"
"1","(-5350,4650)","0","mstr_symbols","I64";
;
VOLTAGE"3.3V"
SIZE"1B"
CDS_LIB"mstr_symbols"
BODY_TYPE"PLUMBING"
HDL_POWER"P3V3_STBY";
"G\NAC"14;
%"GND"
"1","(-5650,2825)","0","mstr_symbols","I68";
;
VOLTAGE"0.0V"
SIZE"1B"
CDS_LIB"mstr_symbols"
BODY_TYPE"PLUMBING"
HDL_POWER"GND";
"A\NAC"15;
%"BLM15AG121SN-1GP"
"1","(-2800,3700)","1","w_hdl","I71";
;
CDS_SEC"1"
CDS_LOCATION"FB25W1"
VALUE"BLM15AG121SN-1GP"
LOCATION"FB25W1"
PACK_TYPE"DISCRET-G"
SEC"1"
SEC_TYPE"DISCRET-G"
PART_NUMBER"68.00084.921"
CDS_LIB"w_hdl"
CDS_LMAN_SYM_OUTLINE"-50,100,50,-100";
"2"
$PN"2"28;
"1"
$PN"1"35;
%"BLM15AG121SN-1GP"
"1","(-2800,3900)","1","w_hdl","I72";
;
CDS_SEC"1"
CDS_LOCATION"FB25W2"
VALUE"BLM15AG121SN-1GP"
LOCATION"FB25W2"
CDS_LMAN_SYM_OUTLINE"-50,100,50,-100"
CDS_LIB"w_hdl"
PART_NUMBER"68.00084.921"
SEC_TYPE"DISCRET-G"
SEC"1"
PACK_TYPE"DISCRET-G";
"2"
$PN"2"27;
"1"
$PN"1"34;
%"BLM15AG121SN-1GP"
"1","(-2800,4100)","1","w_hdl","I73";
;
CDS_SEC"1"
CDS_LOCATION"FB25W3"
VALUE"BLM15AG121SN-1GP"
LOCATION"FB25W3"
PACK_TYPE"DISCRET-G"
SEC"1"
SEC_TYPE"DISCRET-G"
PART_NUMBER"68.00084.921"
CDS_LIB"w_hdl"
CDS_LMAN_SYM_OUTLINE"-50,100,50,-100";
"2"
$PN"2"33;
"1"
$PN"1"30;
%"BLM15AG121SN-1GP"
"1","(-3550,5500)","1","w_hdl","I74";
;
CDS_SEC"1"
CDS_LOCATION"FB25W5"
LOCATION"FB25W5"
VALUE"BLM15AG121SN-1GP"
CDS_LMAN_SYM_OUTLINE"-50,100,50,-100"
CDS_LIB"w_hdl"
PART_NUMBER"68.00084.921"
SEC_TYPE"DISCRET-G"
SEC"1"
PACK_TYPE"DISCRET-G";
"2"
$PN"2"43;
"1"
$PN"1"23;
%"BLM15AG121SN-1GP"
"1","(-3850,5450)","1","w_hdl","I75";
;
CDS_SEC"1"
CDS_LOCATION"FB25W4"
VALUE"BLM15AG121SN-1GP"
LOCATION"FB25W4"
PACK_TYPE"DISCRET-G"
SEC"1"
SEC_TYPE"DISCRET-G"
PART_NUMBER"68.00084.921"
CDS_LIB"w_hdl"
CDS_LMAN_SYM_OUTLINE"-50,100,50,-100";
"2"
$PN"2"42;
"1"
$PN"1"24;
%"TTL1G126_A"
"1","(-7850,4750)","6","mstr_ttl","I76";
;
CDS_SEC"1"
VALUE"74HC1G126"
POWER_GROUP"VCC=P3V3_STBY;GND=GND;"
PART_NUMBER"A79322-001"
MATERIAL"IC"
LOCATION"U25W19"
BOM_COST"SB"
SEC_TYPE"SOT"
CDS_LIB"mstr_ttl"
SEC"1"
ROOM"SB"
PACK_TYPE"SOT"
CDS_LOCATION"U25W19";
"OE"
$PN"1"49;
"Y"
$PN"4"20;
"A"
$PN"2"50;
%"GND"
"1","(-7050,4525)","0","mstr_symbols","I78";
;
SIZE"1B"
VOLTAGE"0.0V"
CDS_LIB"mstr_symbols"
BODY_TYPE"PLUMBING"
HDL_POWER"GND";
"A\NAC"16;
%"CAP_A"
"1","(-7050,4700)","0","dev_discrete","I79";
;
LOCATION"C25W101"
VALUE"0.1UF"
VOLTAGE"16V"
TOLERANCE"10%"
PACK_TYPE"0402V"
MATERIAL"X7R"
PART_NUMBER"A36096-030"
ROOM"UART_MUX"
SEC"1"
CDS_SEC"1"
BOM_COST"DEBUG"
SEC_TYPE"0402V"
CDS_LIB"dev_discrete"
CDS_LOCATION"C25W101";
"B"
$PN"2"16;
"A"
$PN"1"17;
%"P3V3_STBY"
"1","(-7050,4900)","0","mstr_symbols","I80";
;
VOLTAGE"3.3V"
CDS_LIB"mstr_symbols"
SIZE"1B"
BODY_TYPE"PLUMBING"
HDL_POWER"P3V3_STBY";
"G\NAC"17;
END.
